# T6G (Grand Teton) — schematic netlist excerpt (pin names and nets, part order shuffled) for the footprints in the layout excerpt that follows; sources: Cadence DE-HDL packaged netlist, KiCad conversion of 04192023_DAF0TMB3IC0_F0TG_MB_C_brd_V02_OCP.brd

R3634  Q_RES  0.002 1% CHIP  pkg 2512LF  page 237 : A = P3V3_M2_0 ; B = P3V3
R345  Q_RES  49.9 1% EMPTY  pkg 0201LF  page 180 : A = USB2_CPU0_P0_R2_DN ; B = GND
R1144  Q_RES  1K 1% CHIP  pkg 0402LF  page 136 : A = P3V3_AUX ; B = OCP_V3_1_P3V3_PLD_R_PWRGD

(kicad_pcb
	(version 20260206)
	(generator "pcbnew")
	(generator_version "10.0")
	(general
		(thickness 1.6)
		(legacy_teardrops no)
	)
	(paper "A4")
	(title_block
		(title "04192023_DAF0TMB3IC0_F0TG_MB_C_brd_V02_OCP.brd")
		(comment 1 "Grand Teton / footprints 4574-4576 of 8354")
	)
	(layers
		(0 "F.Cu" signal "TOP")
		(4 "In1.Cu" signal "GND")
		(6 "In2.Cu" signal "IN1")
		(8 "In3.Cu" signal "GND1")
		(10 "In4.Cu" signal "IN2")
		(12 "In5.Cu" signal "GND2")
		(14 "In6.Cu" signal "IN3")
		(16 "In7.Cu" signal "GND3")
		(18 "In8.Cu" signal "VCC")
		(20 "In9.Cu" signal "VCC1")
		(22 "In10.Cu" signal "GND4")
		(24 "In11.Cu" signal "IN4")
		(26 "In12.Cu" signal "GND5")
		(28 "In13.Cu" signal "IN5")
		(30 "In14.Cu" signal "GND6")
		(32 "In15.Cu" signal "IN6")
		(34 "In16.Cu" signal "GND7")
		(2 "B.Cu" signal "BOTTOM")
		(9 "F.Adhes" user "F.Adhesive")
		(11 "B.Adhes" user "B.Adhesive")
		(13 "F.Paste" user "Package Geometry/Pastemask Top")
		(15 "B.Paste" user "Package Geometry/Pastemask Bottom")
		(5 "F.SilkS" user "Ref Des/Silkscreen Top")
		(7 "B.SilkS" user "Ref Des/Silkscreen Bottom")
		(1 "F.Mask" user "Board Geometry/Soldermask Top")
		(3 "B.Mask" user "Board Geometry/Soldermask Bottom")
		(17 "Dwgs.User" user "User.Drawings")
		(19 "Cmts.User" user "User.Comments")
		(21 "Eco1.User" user "User.Eco1")
		(23 "Eco2.User" user "User.Eco2")
		(25 "Edge.Cuts" user "Board Geometry/Outline")
		(27 "Margin" user)
		(31 "F.CrtYd" user "Package Geometry/Place Bound Top")
		(29 "B.CrtYd" user "Package Geometry/Place Bound Bottom")
		(35 "F.Fab" user "Ref Des/Assembly Top")
		(33 "B.Fab" user "Ref Des/Assembly Bottom")
	)
	(footprint ""
		(layer "F.Cu")
		(at 166.116 -99.06)
		(property "Reference" "R1144"
			(at 0 0 0)
			(layer "F.SilkS")
			(hide yes)
			(effects
				(font
					(size 1.27 1.27)
				)
			)
		)
		(property "Value" ""
			(at 0 0 0)
			(layer "F.Fab")
			(effects
				(font
					(size 1.27 1.27)
				)
			)
		)
		(duplicate_pad_numbers_are_jumpers no)
		(fp_line
			(start -0.7874 -0.4064)
			(end 0.7874 -0.4064)
			(stroke
				(width 0.1524)
				(type default)
			)
			(layer "F.SilkS")
		)
		(fp_line
			(start -0.7874 0.4064)
			(end -0.7874 -0.4064)
			(stroke
				(width 0.1524)
				(type default)
			)
			(layer "F.SilkS")
		)
		(fp_line
			(start 0.7874 -0.4064)
			(end 0.7874 0.4064)
			(stroke
				(width 0.1524)
				(type default)
			)
			(layer "F.SilkS")
		)
		(fp_line
			(start 0.7874 0.4064)
			(end -0.7874 0.4064)
			(stroke
				(width 0.1524)
				(type default)
			)
			(layer "F.SilkS")
		)
		(fp_line
			(start -0.67945 -0.305054)
			(end -0.12065 -0.305054)
			(stroke
				(width 0.1)
				(type default)
			)
			(layer "F.Fab")
		)
		(fp_line
			(start -0.67945 0.3048)
			(end -0.67945 -0.305054)
			(stroke
				(width 0.1)
				(type default)
			)
			(layer "F.Fab")
		)
		(fp_line
			(start -0.12065 -0.305054)
			(end -0.12065 -0.2794)
			(stroke
				(width 0.1)
				(type default)
			)
			(layer "F.Fab")
		)
		(fp_line
			(start -0.12065 -0.2794)
			(end 0.12065 -0.2794)
			(stroke
				(width 0.1)
				(type default)
			)
			(layer "F.Fab")
		)
		(fp_line
			(start -0.12065 0.2794)
			(end -0.12065 0.3048)
			(stroke
				(width 0.1)
				(type default)
			)
			(layer "F.Fab")
		)
		(fp_line
			(start -0.12065 0.3048)
			(end -0.67945 0.3048)
			(stroke
				(width 0.1)
				(type default)
			)
			(layer "F.Fab")
		)
		(fp_line
			(start 0.120396 0.2794)
			(end -0.12065 0.2794)
			(stroke
				(width 0.1)
				(type default)
			)
			(layer "F.Fab")
		)
		(fp_line
			(start 0.120396 0.3048)
			(end 0.120396 0.2794)
			(stroke
				(width 0.1)
				(type default)
			)
			(layer "F.Fab")
		)
		(fp_line
			(start 0.12065 -0.3048)
			(end 0.67945 -0.3048)
			(stroke
				(width 0.1)
				(type default)
			)
			(layer "F.Fab")
		)
		(fp_line
			(start 0.12065 -0.2794)
			(end 0.12065 -0.3048)
			(stroke
				(width 0.1)
				(type default)
			)
			(layer "F.Fab")
		)
		(fp_line
			(start 0.67945 -0.3048)
			(end 0.67945 0.3048)
			(stroke
				(width 0.1)
				(type default)
			)
			(layer "F.Fab")
		)
		(fp_line
			(start 0.67945 0.3048)
			(end 0.120396 0.3048)
			(stroke
				(width 0.1)
				(type default)
			)
			(layer "F.Fab")
		)
		(pad "1" smd circle
			(at -0.40005 0)
			(size 0 0)
			(layers "F.Cu" "F.Mask" "F.Paste")
			(net "P3V3_AUX")
		)
		(pad "2" smd circle
			(at 0.40005 0)
			(size 0 0)
			(layers "F.Cu" "F.Mask" "F.Paste")
			(net "OCP_V3_1_P3V3_PLD_R_PWRGD")
		)
	)
	(footprint ""
		(layer "F.Cu")
		(at 103.998522 -31.788354 -90)
		(property "Reference" "R345"
			(at 0 0 270)
			(layer "F.SilkS")
			(hide yes)
			(effects
				(font
					(size 1.27 1.27)
				)
			)
		)
		(property "Value" ""
			(at 0 0 270)
			(layer "F.Fab")
			(effects
				(font
					(size 1.27 1.27)
				)
			)
		)
		(duplicate_pad_numbers_are_jumpers no)
		(fp_line
			(start -0.32512 0.175006)
			(end -0.32512 -0.175006)
			(stroke
				(width 0.1)
				(type default)
			)
			(layer "F.Fab")
		)
		(fp_line
			(start 0.32512 0.175006)
			(end -0.32512 0.175006)
			(stroke
				(width 0.1)
				(type default)
			)
			(layer "F.Fab")
		)
		(fp_line
			(start -0.32512 -0.175006)
			(end 0.32512 -0.175006)
			(stroke
				(width 0.1)
				(type default)
			)
			(layer "F.Fab")
		)
		(fp_line
			(start 0.32512 -0.175006)
			(end 0.32512 0.175006)
			(stroke
				(width 0.1)
				(type default)
			)
			(layer "F.Fab")
		)
		(pad "1" smd rect
			(at -0.2667 0 270)
			(size 0.3048 0.381)
			(layers "F.Cu" "F.Mask" "F.Paste")
			(net "USB2_CPU0_P0_R2_DN")
		)
		(pad "2" smd rect
			(at 0.2667 0 90)
			(size 0.3048 0.381)
			(layers "F.Cu" "F.Mask" "F.Paste")
			(net "GND")
		)
	)
	(footprint ""
		(layer "F.Cu")
		(at 164.927026 -58.06821 90)
		(property "Reference" "R3634"
			(at 4.77012 -1.859026 0)
			(unlocked yes)
			(layer "F.SilkS")
			(effects
				(font
					(size 0.7874 0.5842)
					(thickness 0.1524)
				)
				(justify left)
			)
		)
		(property "Value" ""
			(at 0 0 90)
			(layer "F.Fab")
			(effects
				(font
					(size 1.27 1.27)
				)
			)
		)
		(duplicate_pad_numbers_are_jumpers no)
		(fp_line
			(start 3.937508 -1.8796)
			(end -3.937508 -1.8796)
			(stroke
				(width 0.1524)
				(type default)
			)
			(layer "F.SilkS")
		)
		(fp_line
			(start -3.937508 -1.8796)
			(end -3.937508 1.8796)
			(stroke
				(width 0.1524)
				(type default)
			)
			(layer "F.SilkS")
		)
		(fp_line
			(start 3.937508 1.8796)
			(end 3.937508 -1.8796)
			(stroke
				(width 0.1524)
				(type default)
			)
			(layer "F.SilkS")
		)
		(fp_line
			(start -3.937508 1.8796)
			(end 3.937508 1.8796)
			(stroke
				(width 0.1524)
				(type default)
			)
			(layer "F.SilkS")
		)
		(fp_line
			(start 3.275076 -1.674876)
			(end -3.275076 -1.674876)
			(stroke
				(width 0.1)
				(type default)
			)
			(layer "F.Fab")
		)
		(fp_line
			(start -3.275076 -1.674876)
			(end -3.275076 1.674876)
			(stroke
				(width 0.1)
				(type default)
			)
			(layer "F.Fab")
		)
		(fp_line
			(start 3.275076 1.674876)
			(end 3.275076 -1.674876)
			(stroke
				(width 0.1)
				(type default)
			)
			(layer "F.Fab")
		)
		(fp_line
			(start -3.275076 1.674876)
			(end 3.275076 1.674876)
			(stroke
				(width 0.1)
				(type default)
			)
			(layer "F.Fab")
		)
		(pad "1" smd rect
			(at -2.350008 0 90)
			(size 2.921 3.5052)
			(layers "F.Cu" "F.Mask" "F.Paste")
			(net "P3V3_M2_0")
		)
		(pad "2" smd rect
			(at 2.350008 0 90)
			(size 2.921 3.5052)
			(layers "F.Cu" "F.Mask" "F.Paste")
			(net "P3V3")
		)
	)
)
